(kicad_pcb
	(version 20260206)
	(generator "pcbnew")
	(generator_version "10.0")
	(general
		(thickness 1.6)
		(legacy_teardrops no)
	)
	(paper "A4")
	(title_block
		(title "9052_F0T_PDB_Converter_Brick_F_V03_1208_1600_OCP.brd")
		(comment 1 "Grand Teton / footprints 100-102 of 578")
	)
	(layers
		(0 "F.Cu" signal "TOP")
		(4 "In1.Cu" signal "GND")
		(6 "In2.Cu" signal "IN1")
		(8 "In3.Cu" signal "GND1")
		(10 "In4.Cu" signal "VCC")
		(12 "In5.Cu" signal "VCC1")
		(14 "In6.Cu" signal "GND2")
		(16 "In7.Cu" signal "IN2")
		(18 "In8.Cu" signal "GND3")
		(2 "B.Cu" signal "BOTTOM")
		(9 "F.Adhes" user "F.Adhesive")
		(11 "B.Adhes" user "B.Adhesive")
		(13 "F.Paste" user "Package Geometry/Pastemask Top")
		(15 "B.Paste" user "Package Geometry/Pastemask Bottom")
		(5 "F.SilkS" user "Ref Des/Silkscreen Top")
		(7 "B.SilkS" user "Ref Des/Silkscreen Bottom")
		(1 "F.Mask" user "Board Geometry/Soldermask Top")
		(3 "B.Mask" user "Board Geometry/Soldermask Bottom")
		(17 "Dwgs.User" user "User.Drawings")
		(19 "Cmts.User" user "User.Comments")
		(21 "Eco1.User" user "User.Eco1")
		(23 "Eco2.User" user "User.Eco2")
		(25 "Edge.Cuts" user "Board Geometry/Outline")
		(27 "Margin" user)
		(31 "F.CrtYd" user "Package Geometry/Place Bound Top")
		(29 "B.CrtYd" user "Package Geometry/Place Bound Bottom")
		(35 "F.Fab" user "Ref Des/Assembly Top")
		(33 "B.Fab" user "Ref Des/Assembly Bottom")
	)
	(footprint ""
		(layer "F.Cu")
		(at 297.561 -122.9995 180)
		(property "Reference" "PR6957"
			(at 0 0 180)
			(layer "F.SilkS")
			(hide yes)
			(effects
				(font
					(size 1.27 1.27)
				)
			)
		)
		(property "Value" ""
			(at 0 0 180)
			(layer "F.Fab")
			(effects
				(font
					(size 1.27 1.27)
				)
			)
		)
		(duplicate_pad_numbers_are_jumpers no)
		(fp_line
			(start 1.2954 0.5842)
			(end -1.2954 0.5842)
			(stroke
				(width 0.1524)
				(type default)
			)
			(layer "F.SilkS")
		)
		(fp_line
			(start 1.2954 -0.5842)
			(end 1.2954 0.5842)
			(stroke
				(width 0.1524)
				(type default)
			)
			(layer "F.SilkS")
		)
		(fp_line
			(start -1.2954 0.5842)
			(end -1.2954 -0.5842)
			(stroke
				(width 0.1524)
				(type default)
			)
			(layer "F.SilkS")
		)
		(fp_line
			(start -1.2954 -0.5842)
			(end 1.2954 -0.5842)
			(stroke
				(width 0.1524)
				(type default)
			)
			(layer "F.SilkS")
		)
		(fp_line
			(start 1.1938 0.4064)
			(end 0.8636 0.4064)
			(stroke
				(width 0.1)
				(type default)
			)
			(layer "F.Fab")
		)
		(fp_line
			(start 1.1938 -0.406654)
			(end 1.1938 0.4064)
			(stroke
				(width 0.1)
				(type default)
			)
			(layer "F.Fab")
		)
		(fp_line
			(start 0.8636 0.4572)
			(end -0.8636 0.4572)
			(stroke
				(width 0.1)
				(type default)
			)
			(layer "F.Fab")
		)
		(fp_line
			(start 0.8636 0.4064)
			(end 0.8636 0.4572)
			(stroke
				(width 0.1)
				(type default)
			)
			(layer "F.Fab")
		)
		(fp_line
			(start 0.8636 -0.406654)
			(end 1.1938 -0.406654)
			(stroke
				(width 0.1)
				(type default)
			)
			(layer "F.Fab")
		)
		(fp_line
			(start 0.8636 -0.4572)
			(end 0.8636 -0.406654)
			(stroke
				(width 0.1)
				(type default)
			)
			(layer "F.Fab")
		)
		(fp_line
			(start -0.8636 0.4572)
			(end -0.8636 0.4318)
			(stroke
				(width 0.1)
				(type default)
			)
			(layer "F.Fab")
		)
		(fp_line
			(start -0.8636 0.4318)
			(end -0.8636 0.4064)
			(stroke
				(width 0.1)
				(type default)
			)
			(layer "F.Fab")
		)
		(fp_line
			(start -0.8636 0.4064)
			(end -1.1938 0.4064)
			(stroke
				(width 0.1)
				(type default)
			)
			(layer "F.Fab")
		)
		(fp_line
			(start -0.8636 -0.406654)
			(end -0.8636 -0.4572)
			(stroke
				(width 0.1)
				(type default)
			)
			(layer "F.Fab")
		)
		(fp_line
			(start -0.8636 -0.4572)
			(end 0.8636 -0.4572)
			(stroke
				(width 0.1)
				(type default)
			)
			(layer "F.Fab")
		)
		(fp_line
			(start -1.1938 0.4064)
			(end -1.1938 -0.406654)
			(stroke
				(width 0.1)
				(type default)
			)
			(layer "F.Fab")
		)
		(fp_line
			(start -1.1938 -0.406654)
			(end -0.8636 -0.406654)
			(stroke
				(width 0.1)
				(type default)
			)
			(layer "F.Fab")
		)
		(pad "1" smd rect
			(at -0.7366 0 90)
			(size 0.7112 0.8128)
			(layers "F.Cu" "F.Mask" "F.Paste")
			(net "P52V_HS_4287_S1N")
		)
		(pad "2" smd rect
			(at 0.7366 0 90)
			(size 0.7112 0.8128)
			(layers "F.Cu" "F.Mask" "F.Paste")
			(net "P52V_HS1_SENSE_N_R1")
		)
	)
	(footprint ""
		(layer "F.Cu")
		(at 180.34 -10.287 90)
		(property "Reference" "PR314"
			(at 0 0 90)
			(layer "F.SilkS")
			(hide yes)
			(effects
				(font
					(size 1.27 1.27)
				)
			)
		)
		(property "Value" ""
			(at 0 0 90)
			(layer "F.Fab")
			(effects
				(font
					(size 1.27 1.27)
				)
			)
		)
		(duplicate_pad_numbers_are_jumpers no)
		(fp_line
			(start 0.7874 -0.4064)
			(end 0.7874 0.4064)
			(stroke
				(width 0.1524)
				(type default)
			)
			(layer "F.SilkS")
		)
		(fp_line
			(start -0.7874 -0.4064)
			(end 0.7874 -0.4064)
			(stroke
				(width 0.1524)
				(type default)
			)
			(layer "F.SilkS")
		)
		(fp_line
			(start 0.7874 0.4064)
			(end -0.7874 0.4064)
			(stroke
				(width 0.1524)
				(type default)
			)
			(layer "F.SilkS")
		)
		(fp_line
			(start -0.7874 0.4064)
			(end -0.7874 -0.4064)
			(stroke
				(width 0.1524)
				(type default)
			)
			(layer "F.SilkS")
		)
		(fp_line
			(start -0.12065 -0.305054)
			(end -0.12065 -0.2794)
			(stroke
				(width 0.1)
				(type default)
			)
			(layer "F.Fab")
		)
		(fp_line
			(start -0.67945 -0.305054)
			(end -0.12065 -0.305054)
			(stroke
				(width 0.1)
				(type default)
			)
			(layer "F.Fab")
		)
		(fp_line
			(start 0.67945 -0.3048)
			(end 0.67945 0.3048)
			(stroke
				(width 0.1)
				(type default)
			)
			(layer "F.Fab")
		)
		(fp_line
			(start 0.12065 -0.3048)
			(end 0.67945 -0.3048)
			(stroke
				(width 0.1)
				(type default)
			)
			(layer "F.Fab")
		)
		(fp_line
			(start 0.12065 -0.2794)
			(end 0.12065 -0.3048)
			(stroke
				(width 0.1)
				(type default)
			)
			(layer "F.Fab")
		)
		(fp_line
			(start -0.12065 -0.2794)
			(end 0.12065 -0.2794)
			(stroke
				(width 0.1)
				(type default)
			)
			(layer "F.Fab")
		)
		(fp_line
			(start 0.120396 0.2794)
			(end -0.12065 0.2794)
			(stroke
				(width 0.1)
				(type default)
			)
			(layer "F.Fab")
		)
		(fp_line
			(start -0.12065 0.2794)
			(end -0.12065 0.3048)
			(stroke
				(width 0.1)
				(type default)
			)
			(layer "F.Fab")
		)
		(fp_line
			(start 0.67945 0.3048)
			(end 0.120396 0.3048)
			(stroke
				(width 0.1)
				(type default)
			)
			(layer "F.Fab")
		)
		(fp_line
			(start 0.120396 0.3048)
			(end 0.120396 0.2794)
			(stroke
				(width 0.1)
				(type default)
			)
			(layer "F.Fab")
		)
		(fp_line
			(start -0.12065 0.3048)
			(end -0.67945 0.3048)
			(stroke
				(width 0.1)
				(type default)
			)
			(layer "F.Fab")
		)
		(fp_line
			(start -0.67945 0.3048)
			(end -0.67945 -0.305054)
			(stroke
				(width 0.1)
				(type default)
			)
			(layer "F.Fab")
		)
		(pad "1" smd circle
			(at -0.40005 0 90)
			(size 0 0)
			(layers "F.Cu" "F.Mask" "F.Paste")
			(net "SW_P3V3_AUX_BT")
		)
		(pad "2" smd circle
			(at 0.40005 0 90)
			(size 0 0)
			(layers "F.Cu" "F.Mask" "F.Paste")
			(net "SW_P3V3_AUX_BT_R")
		)
	)
	(footprint ""
		(layer "F.Cu")
		(at 8.58012 -79.939896)
		(property "Reference" "J7"
			(at 4.50088 -18.077434 0)
			(unlocked yes)
			(layer "F.SilkS")
			(effects
				(font
					(size 0.7874 0.5842)
					(thickness 0.1524)
				)
				(justify left)
			)
		)
		(property "Value" ""
			(at 0 0 0)
			(layer "F.Fab")
			(effects
				(font
					(size 1.27 1.27)
				)
			)
		)
		(duplicate_pad_numbers_are_jumpers no)
		(fp_line
			(start -14.51991 -17.210024)
			(end 5.679948 -17.210024)
			(stroke
				(width 0.1524)
				(type default)
			)
			(layer "F.SilkS")
		)
		(fp_line
			(start -14.51991 29.29001)
			(end -14.51991 -17.210024)
			(stroke
				(width 0.1524)
				(type default)
			)
			(layer "F.SilkS")
		)
		(fp_line
			(start 5.679948 -17.210024)
			(end 5.679948 29.29001)
			(stroke
				(width 0.1524)
				(type default)
			)
			(layer "F.SilkS")
		)
		(fp_line
			(start 5.679948 29.29001)
			(end -14.51991 29.29001)
			(stroke
				(width 0.1524)
				(type default)
			)
			(layer "F.SilkS")
		)
		(fp_poly
			(pts
				(xy 6.93928 0.564896) (xy 6.93928 -0.451104) (xy 5.92328 0.056896)
			)
			(stroke
				(width 0)
				(type default)
			)
			(fill yes)
			(layer "F.SilkS")
		)
		(fp_line
			(start -14.51991 -17.210024)
			(end 5.679948 -17.210024)
			(stroke
				(width 0.1)
				(type default)
			)
			(layer "F.Fab")
		)
		(fp_line
			(start -14.51991 29.29001)
			(end -14.51991 -17.210024)
			(stroke
				(width 0.1)
				(type default)
			)
			(layer "F.Fab")
		)
		(fp_line
			(start 5.679948 -17.210024)
			(end 5.679948 29.29001)
			(stroke
				(width 0.1)
				(type default)
			)
			(layer "F.Fab")
		)
		(fp_line
			(start 5.679948 29.29001)
			(end -14.51991 29.29001)
			(stroke
				(width 0.1)
				(type default)
			)
			(layer "F.Fab")
		)
		(fp_poly
			(pts
				(xy -15.693898 -0.508) (xy -15.693898 0.508) (xy -14.677898 0)
			)
			(stroke
				(width 0)
				(type default)
			)
			(fill yes)
			(layer "F.Fab")
		)
		(pad "" np_thru_hole circle
			(at -3.519932 -13.459968 270)
			(size 2.2098 2.2098)
			(drill 2.2098)
			(layers "*.Cu" "*.Mask")
			(clearance 0.381)
			(thermal_gap 0.381)
		)
		(pad "" np_thru_hole circle
			(at -3.519932 25.539954 270)
			(size 2.2098 2.2098)
			(drill 2.2098)
			(layers "*.Cu" "*.Mask")
			(clearance 0.381)
			(thermal_gap 0.381)
		)
		(pad "P1" thru_hole circle
			(at 1.27 20.860004 270)
			(size 1.4732 1.4732)
			(drill 1.0414)
			(layers "*.Cu" "*.Mask")
			(remove_unused_layers no)
			(net "GND")
			(clearance 0.0381)
			(thermal_gap 0.0381)
		)
		(pad "P2" thru_hole circle
			(at 1.27 19.159982 270)
			(size 1.4732 1.4732)
			(drill 1.0414)
			(layers "*.Cu" "*.Mask")
			(remove_unused_layers no)
			(net "GND")
			(clearance 0.0381)
			(thermal_gap 0.0381)
		)
		(pad "P3" thru_hole circle
			(at 1.27 15.780004 270)
			(size 1.4732 1.4732)
			(drill 1.0414)
			(layers "*.Cu" "*.Mask")
			(remove_unused_layers no)
			(net "GND")
			(clearance 0.0381)
			(thermal_gap 0.0381)
		)
		(pad "P4" thru_hole circle
			(at 1.27 14.079982 270)
			(size 1.4732 1.4732)
			(drill 1.0414)
			(layers "*.Cu" "*.Mask")
			(remove_unused_layers no)
			(net "GND")
			(clearance 0.0381)
			(thermal_gap 0.0381)
		)
		(pad "P5" thru_hole circle
			(at 1.27 10.700004 270)
			(size 1.4732 1.4732)
			(drill 1.0414)
			(layers "*.Cu" "*.Mask")
			(remove_unused_layers no)
			(net "P52V_FAN")
			(clearance 0.0381)
			(thermal_gap 0.0381)
		)
		(pad "P6" thru_hole circle
			(at 1.27 8.999982 270)
			(size 1.4732 1.4732)
			(drill 1.0414)
			(layers "*.Cu" "*.Mask")
			(remove_unused_layers no)
			(net "P52V_FAN")
			(clearance 0.0381)
			(thermal_gap 0.0381)
		)
		(pad "P7" thru_hole circle
			(at 1.27 5.620004 270)
			(size 1.4732 1.4732)
			(drill 1.0414)
			(layers "*.Cu" "*.Mask")
			(remove_unused_layers no)
			(net "P52V_FAN")
			(clearance 0.0381)
			(thermal_gap 0.0381)
		)
		(pad "P8" thru_hole circle
			(at 1.27 3.919982 270)
			(size 1.4732 1.4732)
			(drill 1.0414)
			(layers "*.Cu" "*.Mask")
			(remove_unused_layers no)
			(net "P52V_FAN")
			(clearance 0.0381)
			(thermal_gap 0.0381)
		)
		(pad "P9" thru_hole circle
			(at 3.81 3.919982 270)
			(size 1.4732 1.4732)
			(drill 1.0414)
			(layers "*.Cu" "*.Mask")
			(remove_unused_layers no)
			(net "P52V_FAN")
			(clearance 0.0381)
			(thermal_gap 0.0381)
		)
		(pad "P10" thru_hole circle
			(at 3.81 5.620004 270)
			(size 1.4732 1.4732)
			(drill 1.0414)
			(layers "*.Cu" "*.Mask")
			(remove_unused_layers no)
			(net "P52V_FAN")
			(clearance 0.0381)
			(thermal_gap 0.0381)
		)
		(pad "P11" thru_hole circle
			(at 3.81 8.999982 270)
			(size 1.4732 1.4732)
			(drill 1.0414)
			(layers "*.Cu" "*.Mask")
			(remove_unused_layers no)
			(net "P52V_FAN")
			(clearance 0.0381)
			(thermal_gap 0.0381)
		)
		(pad "P12" thru_hole circle
			(at 3.81 10.700004 270)
			(size 1.4732 1.4732)
			(drill 1.0414)
			(layers "*.Cu" "*.Mask")
			(remove_unused_layers no)
			(net "P52V_FAN")
			(clearance 0.0381)
			(thermal_gap 0.0381)
		)
		(pad "P13" thru_hole circle
			(at 3.81 14.079982 270)
			(size 1.4732 1.4732)
			(drill 1.0414)
			(layers "*.Cu" "*.Mask")
			(remove_unused_layers no)
			(net "GND")
			(clearance 0.0381)
			(thermal_gap 0.0381)
		)
		(pad "P14" thru_hole circle
			(at 3.81 15.780004 270)
			(size 1.4732 1.4732)
			(drill 1.0414)
			(layers "*.Cu" "*.Mask")
			(remove_unused_layers no)
			(net "GND")
			(clearance 0.0381)
			(thermal_gap 0.0381)
		)
		(pad "P15" thru_hole circle
			(at 3.81 19.159982 270)
			(size 1.4732 1.4732)
			(drill 1.0414)
			(layers "*.Cu" "*.Mask")
			(remove_unused_layers no)
			(net "GND")
			(clearance 0.0381)
			(thermal_gap 0.0381)
		)
		(pad "P16" thru_hole circle
			(at 3.81 20.860004 270)
			(size 1.4732 1.4732)
			(drill 1.0414)
			(layers "*.Cu" "*.Mask")
			(remove_unused_layers no)
			(net "GND")
			(clearance 0.0381)
			(thermal_gap 0.0381)
		)
		(pad "S1" thru_hole rect
			(at 0 0 270)
			(size 1.27 1.27)
			(drill 0.8636)
			(layers "*.Cu" "*.Mask")
			(remove_unused_layers no)
			(net "PRSNT_HPDB_N")
			(clearance 0.0508)
			(thermal_gap 0.0508)
			(padstack
				(mode front_inner_back)
				(layer "Inner"
					(shape circle)
					(size 1.27 1.27)
					(clearance 0.0508)
				)
				(layer "B.Cu"
					(shape rect)
					(size 1.27 1.27)
					(clearance 0.0508)
				)
			)
		)
		(pad "S2" thru_hole circle
			(at 1.27 -1.27 270)
			(size 1.27 1.27)
			(drill 0.8636)
			(layers "*.Cu" "*.Mask")
			(remove_unused_layers no)
			(net "PWRGD_P3V3_HPDB")
			(clearance 0.0508)
			(thermal_gap 0.0508)
		)
		(pad "S3" thru_hole circle
			(at 0 -2.54 270)
			(size 1.27 1.27)
			(drill 0.8636)
			(layers "*.Cu" "*.Mask")
			(remove_unused_layers no)
			(net "GND")
			(clearance 0.0508)
			(thermal_gap 0.0508)
		)
		(pad "S4" thru_hole circle
			(at 1.27 -3.81 270)
			(size 1.27 1.27)
			(drill 0.8636)
			(layers "*.Cu" "*.Mask")
			(remove_unused_layers no)
			(net "PWRGD_GPU_HSC")
			(clearance 0.0508)
			(thermal_gap 0.0508)
		)
		(pad "S5" thru_hole circle
			(at 0 -5.08 270)
			(size 1.27 1.27)
			(drill 0.8636)
			(layers "*.Cu" "*.Mask")
			(remove_unused_layers no)
			(net "SMB_P52V_HPDB_R_SDA")
			(clearance 0.0508)
			(thermal_gap 0.0508)
		)
		(pad "S6" thru_hole circle
			(at 1.27 -6.35 270)
			(size 1.27 1.27)
			(drill 0.8636)
			(layers "*.Cu" "*.Mask")
			(remove_unused_layers no)
			(net "SMB_P52V_HPDB_R_SCL")
			(clearance 0.0508)
			(thermal_gap 0.0508)
		)
		(pad "S7" thru_hole circle
			(at 0 -7.62 270)
			(size 1.27 1.27)
			(drill 0.8636)
			(layers "*.Cu" "*.Mask")
			(remove_unused_layers no)
			(net "SMB_HPDB_MISC_R_SDA")
			(clearance 0.0508)
			(thermal_gap 0.0508)
		)
		(pad "S8" thru_hole circle
			(at 1.27 -8.89 270)
			(size 1.27 1.27)
			(drill 0.8636)
			(layers "*.Cu" "*.Mask")
			(remove_unused_layers no)
			(net "SMB_HPDB_MISC_R_SCL")
			(clearance 0.0508)
			(thermal_gap 0.0508)
		)
		(pad "S9" thru_hole circle
			(at 3.81 -8.89 270)
			(size 1.27 1.27)
			(drill 0.8636)
			(layers "*.Cu" "*.Mask")
			(remove_unused_layers no)
			(net "P12V_HPDB")
			(clearance 0.0508)
			(thermal_gap 0.0508)
		)
		(pad "S10" thru_hole circle
			(at 2.54 -7.62 270)
			(size 1.27 1.27)
			(drill 0.8636)
			(layers "*.Cu" "*.Mask")
			(remove_unused_layers no)
			(net "P12V_HPDB")
			(clearance 0.0508)
			(thermal_gap 0.0508)
		)
		(pad "S11" thru_hole circle
			(at 3.81 -6.35 270)
			(size 1.27 1.27)
			(drill 0.8636)
			(layers "*.Cu" "*.Mask")
			(remove_unused_layers no)
			(net "PWRGD_P3V3_AUX_MB_BUF")
			(clearance 0.0508)
			(thermal_gap 0.0508)
		)
		(pad "S12" thru_hole circle
			(at 2.54 -5.08 270)
			(size 1.27 1.27)
			(drill 0.8636)
			(layers "*.Cu" "*.Mask")
			(remove_unused_layers no)
			(net "FAN_PWR_EN_BUF")
			(clearance 0.0508)
			(thermal_gap 0.0508)
		)
		(pad "S13" thru_hole circle
			(at 3.81 -3.81 270)
			(size 1.27 1.27)
			(drill 0.8636)
			(layers "*.Cu" "*.Mask")
			(remove_unused_layers no)
			(net "P12V_HPDB")
			(clearance 0.0508)
			(thermal_gap 0.0508)
		)
		(pad "S14" thru_hole circle
			(at 2.54 -2.54 270)
			(size 1.27 1.27)
			(drill 0.8636)
			(layers "*.Cu" "*.Mask")
			(remove_unused_layers no)
			(net "GPU_HSC_EN")
			(clearance 0.0508)
			(thermal_gap 0.0508)
		)
		(pad "S15" thru_hole circle
			(at 3.81 -1.27 270)
			(size 1.27 1.27)
			(drill 0.8636)
			(layers "*.Cu" "*.Mask")
			(remove_unused_layers no)
			(net "RST_SMB_PDB_BUF_N")
			(clearance 0.0508)
			(thermal_gap 0.0508)
		)
		(pad "S16" thru_hole circle
			(at 2.54 0 270)
			(size 1.27 1.27)
			(drill 0.8636)
			(layers "*.Cu" "*.Mask")
			(remove_unused_layers no)
			(net "P12V_HPDB_PWRGD")
			(clearance 0.0508)
			(thermal_gap 0.0508)
		)
		(zone
			(layers "F.Cu" "B.Cu" "In1.Cu" "In2.Cu" "In3.Cu" "In4.Cu" "In5.Cu" "In6.Cu"
				"In7.Cu" "In8.Cu"
			)
			(hatch none 0.5)
			(connect_pads
				(clearance 0)
			)
			(min_thickness 0.25)
			(keepout
				(tracks not_allowed)
				(vias allowed)
				(pads allowed)
				(copperpour not_allowed)
				(footprints allowed)
			)
			(placement
				(enabled no)
				(sheetname "")
			)
			(fill
				(thermal_gap 0.5)
				(thermal_bridge_width 0.5)
				(island_removal_mode 0)
			)
			(polygon
				(pts
					(arc
						(start 6.673088 -93.399864)
						(mid 3.447288 -93.399864)
						(end 6.673088 -93.399864)
					)
				)
			)
		)
		(zone
			(layers "F.Cu" "B.Cu" "In1.Cu" "In2.Cu" "In3.Cu" "In4.Cu" "In5.Cu" "In6.Cu"
				"In7.Cu" "In8.Cu"
			)
			(hatch none 0.5)
			(connect_pads
				(clearance 0)
			)
			(min_thickness 0.25)
			(keepout
				(tracks not_allowed)
				(vias allowed)
				(pads allowed)
				(copperpour not_allowed)
				(footprints allowed)
			)
			(placement
				(enabled no)
				(sheetname "")
			)
			(fill
				(thermal_gap 0.5)
				(thermal_bridge_width 0.5)
				(island_removal_mode 0)
			)
			(polygon
				(pts
					(arc
						(start 6.673088 -54.399942)
						(mid 3.447288 -54.399942)
						(end 6.673088 -54.399942)
					)
				)
			)
		)
	)
)
